# T6G (Grand Teton) — schematic netlist excerpt (pin names and nets, part order shuffled) for the footprints in the layout excerpt that follows; sources: Cadence DE-HDL packaged netlist, KiCad conversion of 04192023_DAF0TMB3IC0_F0TG_MB_C_brd_V02_OCP.brd

C250  Q_CAP  10UF 6.3V 20% X6S  pkg C0402  page 323 : A = P0V9_CPU1_RT0_2A ; B = GND
PR112  Q_RES  0 5% CHIP  pkg 0402LF  page 206 : A = PVDDIO_P0_VOS4 ; B = PVDDIO_P0
PC8013  Q_CAP  22UF 16V 20% X6S  pkg C0805  page 190 : A = SW_P3V3_AUX_FLT ; B = GND

(kicad_pcb
	(version 20260206)
	(generator "pcbnew")
	(generator_version "10.0")
	(general
		(thickness 1.6)
		(legacy_teardrops no)
	)
	(paper "A4")
	(title_block
		(title "04192023_DAF0TMB3IC0_F0TG_MB_C_brd_V02_OCP.brd")
		(comment 1 "Grand Teton / footprints 7853-7855 of 8354")
	)
	(layers
		(0 "F.Cu" signal "TOP")
		(4 "In1.Cu" signal "GND")
		(6 "In2.Cu" signal "IN1")
		(8 "In3.Cu" signal "GND1")
		(10 "In4.Cu" signal "IN2")
		(12 "In5.Cu" signal "GND2")
		(14 "In6.Cu" signal "IN3")
		(16 "In7.Cu" signal "GND3")
		(18 "In8.Cu" signal "VCC")
		(20 "In9.Cu" signal "VCC1")
		(22 "In10.Cu" signal "GND4")
		(24 "In11.Cu" signal "IN4")
		(26 "In12.Cu" signal "GND5")
		(28 "In13.Cu" signal "IN5")
		(30 "In14.Cu" signal "GND6")
		(32 "In15.Cu" signal "IN6")
		(34 "In16.Cu" signal "GND7")
		(2 "B.Cu" signal "BOTTOM")
		(9 "F.Adhes" user "F.Adhesive")
		(11 "B.Adhes" user "B.Adhesive")
		(13 "F.Paste" user "Package Geometry/Pastemask Top")
		(15 "B.Paste" user "Package Geometry/Pastemask Bottom")
		(5 "F.SilkS" user "Ref Des/Silkscreen Top")
		(7 "B.SilkS" user "Ref Des/Silkscreen Bottom")
		(1 "F.Mask" user "Board Geometry/Soldermask Top")
		(3 "B.Mask" user "Board Geometry/Soldermask Bottom")
		(17 "Dwgs.User" user "User.Drawings")
		(19 "Cmts.User" user "User.Comments")
		(21 "Eco1.User" user "User.Eco1")
		(23 "Eco2.User" user "User.Eco2")
		(25 "Edge.Cuts" user "Board Geometry/Outline")
		(27 "Margin" user)
		(31 "F.CrtYd" user "Package Geometry/Place Bound Top")
		(29 "B.CrtYd" user "Package Geometry/Place Bound Bottom")
		(35 "F.Fab" user "Ref Des/Assembly Top")
		(33 "B.Fab" user "Ref Des/Assembly Bottom")
	)
	(footprint ""
		(layer "B.Cu")
		(at 448.051682 -53.20411 -90)
		(property "Reference" "PC8013"
			(at 0 0 90)
			(layer "B.SilkS")
			(hide yes)
			(effects
				(font
					(size 1.27 1.27)
				)
				(justify mirror)
			)
		)
		(property "Value" ""
			(at 0 0 90)
			(layer "B.Fab")
			(effects
				(font
					(size 1.27 1.27)
				)
				(justify mirror)
			)
		)
		(duplicate_pad_numbers_are_jumpers no)
		(fp_line
			(start -1.524 0.762)
			(end 1.524 0.762)
			(stroke
				(width 0.1524)
				(type default)
			)
			(layer "B.SilkS")
		)
		(fp_line
			(start 1.524 0.762)
			(end 1.524 -0.762)
			(stroke
				(width 0.1524)
				(type default)
			)
			(layer "B.SilkS")
		)
		(fp_line
			(start -1.524 -0.762)
			(end -1.524 0.762)
			(stroke
				(width 0.1524)
				(type default)
			)
			(layer "B.SilkS")
		)
		(fp_line
			(start 1.524 -0.762)
			(end -1.524 -0.762)
			(stroke
				(width 0.1524)
				(type default)
			)
			(layer "B.SilkS")
		)
		(fp_line
			(start -1.1049 0.724916)
			(end -1.1049 -0.724916)
			(stroke
				(width 0.1)
				(type default)
			)
			(layer "B.Fab")
		)
		(fp_line
			(start 1.1049 0.724916)
			(end -1.1049 0.724916)
			(stroke
				(width 0.1)
				(type default)
			)
			(layer "B.Fab")
		)
		(fp_line
			(start -1.1049 -0.724916)
			(end 1.1049 -0.724916)
			(stroke
				(width 0.1)
				(type default)
			)
			(layer "B.Fab")
		)
		(fp_line
			(start 1.1049 -0.724916)
			(end 1.1049 0.724916)
			(stroke
				(width 0.1)
				(type default)
			)
			(layer "B.Fab")
		)
		(pad "1" smd rect
			(at 0.889 0 270)
			(size 1.016 1.27)
			(layers "B.Cu" "B.Mask" "B.Paste")
			(net "SW_P3V3_AUX_FLT")
		)
		(pad "2" smd rect
			(at -0.889 0 270)
			(size 1.016 1.27)
			(layers "B.Cu" "B.Mask" "B.Paste")
			(net "GND")
		)
	)
	(footprint ""
		(layer "B.Cu")
		(at 47.391066 -390.560052 90)
		(property "Reference" "C250"
			(at 0 0 90)
			(layer "B.SilkS")
			(hide yes)
			(effects
				(font
					(size 1.27 1.27)
				)
				(justify mirror)
			)
		)
		(property "Value" ""
			(at 0 0 90)
			(layer "B.Fab")
			(effects
				(font
					(size 1.27 1.27)
				)
				(justify mirror)
			)
		)
		(duplicate_pad_numbers_are_jumpers no)
		(fp_line
			(start 0.7874 -0.4064)
			(end -0.7874 -0.4064)
			(stroke
				(width 0.1524)
				(type default)
			)
			(layer "B.SilkS")
		)
		(fp_line
			(start -0.7874 -0.4064)
			(end -0.7874 0.4064)
			(stroke
				(width 0.1524)
				(type default)
			)
			(layer "B.SilkS")
		)
		(fp_line
			(start 0.7874 0.4064)
			(end 0.7874 -0.4064)
			(stroke
				(width 0.1524)
				(type default)
			)
			(layer "B.SilkS")
		)
		(fp_line
			(start -0.7874 0.4064)
			(end 0.7874 0.4064)
			(stroke
				(width 0.1524)
				(type default)
			)
			(layer "B.SilkS")
		)
		(fp_line
			(start 0.67945 -0.305054)
			(end 0.12065 -0.305054)
			(stroke
				(width 0.1)
				(type default)
			)
			(layer "B.Fab")
		)
		(fp_line
			(start 0.12065 -0.305054)
			(end 0.12065 -0.2794)
			(stroke
				(width 0.1)
				(type default)
			)
			(layer "B.Fab")
		)
		(fp_line
			(start -0.12065 -0.3048)
			(end -0.67945 -0.3048)
			(stroke
				(width 0.1)
				(type default)
			)
			(layer "B.Fab")
		)
		(fp_line
			(start -0.67945 -0.3048)
			(end -0.67945 0.3048)
			(stroke
				(width 0.1)
				(type default)
			)
			(layer "B.Fab")
		)
		(fp_line
			(start 0.12065 -0.2794)
			(end -0.12065 -0.2794)
			(stroke
				(width 0.1)
				(type default)
			)
			(layer "B.Fab")
		)
		(fp_line
			(start -0.12065 -0.2794)
			(end -0.12065 -0.3048)
			(stroke
				(width 0.1)
				(type default)
			)
			(layer "B.Fab")
		)
		(fp_line
			(start 0.12065 0.2794)
			(end 0.12065 0.3048)
			(stroke
				(width 0.1)
				(type default)
			)
			(layer "B.Fab")
		)
		(fp_line
			(start -0.120396 0.2794)
			(end 0.12065 0.2794)
			(stroke
				(width 0.1)
				(type default)
			)
			(layer "B.Fab")
		)
		(fp_line
			(start 0.67945 0.3048)
			(end 0.67945 -0.305054)
			(stroke
				(width 0.1)
				(type default)
			)
			(layer "B.Fab")
		)
		(fp_line
			(start 0.12065 0.3048)
			(end 0.67945 0.3048)
			(stroke
				(width 0.1)
				(type default)
			)
			(layer "B.Fab")
		)
		(fp_line
			(start -0.120396 0.3048)
			(end -0.120396 0.2794)
			(stroke
				(width 0.1)
				(type default)
			)
			(layer "B.Fab")
		)
		(fp_line
			(start -0.67945 0.3048)
			(end -0.120396 0.3048)
			(stroke
				(width 0.1)
				(type default)
			)
			(layer "B.Fab")
		)
		(pad "1" smd circle
			(at 0.40005 0 270)
			(size 0 0)
			(layers "B.Cu" "B.Mask" "B.Paste")
			(net "P0V9_CPU1_RT0_2A")
		)
		(pad "2" smd circle
			(at -0.40005 0 270)
			(size 0 0)
			(layers "B.Cu" "B.Mask" "B.Paste")
			(net "GND")
		)
	)
	(footprint ""
		(layer "B.Cu")
		(at 271.760696 -349.381572 -90)
		(property "Reference" "PR112"
			(at 0 0 90)
			(layer "B.SilkS")
			(hide yes)
			(effects
				(font
					(size 1.27 1.27)
				)
				(justify mirror)
			)
		)
		(property "Value" ""
			(at 0 0 90)
			(layer "B.Fab")
			(effects
				(font
					(size 1.27 1.27)
				)
				(justify mirror)
			)
		)
		(duplicate_pad_numbers_are_jumpers no)
		(fp_line
			(start -0.7874 0.4064)
			(end 0.7874 0.4064)
			(stroke
				(width 0.1524)
				(type default)
			)
			(layer "B.SilkS")
		)
		(fp_line
			(start 0.7874 0.4064)
			(end 0.7874 -0.4064)
			(stroke
				(width 0.1524)
				(type default)
			)
			(layer "B.SilkS")
		)
		(fp_line
			(start -0.7874 -0.4064)
			(end -0.7874 0.4064)
			(stroke
				(width 0.1524)
				(type default)
			)
			(layer "B.SilkS")
		)
		(fp_line
			(start 0.7874 -0.4064)
			(end -0.7874 -0.4064)
			(stroke
				(width 0.1524)
				(type default)
			)
			(layer "B.SilkS")
		)
		(fp_line
			(start -0.67945 0.3048)
			(end -0.120396 0.3048)
			(stroke
				(width 0.1)
				(type default)
			)
			(layer "B.Fab")
		)
		(fp_line
			(start -0.120396 0.3048)
			(end -0.120396 0.2794)
			(stroke
				(width 0.1)
				(type default)
			)
			(layer "B.Fab")
		)
		(fp_line
			(start 0.12065 0.3048)
			(end 0.67945 0.3048)
			(stroke
				(width 0.1)
				(type default)
			)
			(layer "B.Fab")
		)
		(fp_line
			(start 0.67945 0.3048)
			(end 0.67945 -0.305054)
			(stroke
				(width 0.1)
				(type default)
			)
			(layer "B.Fab")
		)
		(fp_line
			(start -0.120396 0.2794)
			(end 0.12065 0.2794)
			(stroke
				(width 0.1)
				(type default)
			)
			(layer "B.Fab")
		)
		(fp_line
			(start 0.12065 0.2794)
			(end 0.12065 0.3048)
			(stroke
				(width 0.1)
				(type default)
			)
			(layer "B.Fab")
		)
		(fp_line
			(start -0.12065 -0.2794)
			(end -0.12065 -0.3048)
			(stroke
				(width 0.1)
				(type default)
			)
			(layer "B.Fab")
		)
		(fp_line
			(start 0.12065 -0.2794)
			(end -0.12065 -0.2794)
			(stroke
				(width 0.1)
				(type default)
			)
			(layer "B.Fab")
		)
		(fp_line
			(start -0.67945 -0.3048)
			(end -0.67945 0.3048)
			(stroke
				(width 0.1)
				(type default)
			)
			(layer "B.Fab")
		)
		(fp_line
			(start -0.12065 -0.3048)
			(end -0.67945 -0.3048)
			(stroke
				(width 0.1)
				(type default)
			)
			(layer "B.Fab")
		)
		(fp_line
			(start 0.12065 -0.305054)
			(end 0.12065 -0.2794)
			(stroke
				(width 0.1)
				(type default)
			)
			(layer "B.Fab")
		)
		(fp_line
			(start 0.67945 -0.305054)
			(end 0.12065 -0.305054)
			(stroke
				(width 0.1)
				(type default)
			)
			(layer "B.Fab")
		)
		(pad "1" smd circle
			(at 0.40005 0 90)
			(size 0 0)
			(layers "B.Cu" "B.Mask" "B.Paste")
			(net "PVDDIO_P0_VOS4")
		)
		(pad "2" smd circle
			(at -0.40005 0 90)
			(size 0 0)
			(layers "B.Cu" "B.Mask" "B.Paste")
			(net "PVDDIO_P0")
		)
	)
)
